(kicad_pcb
	(version 20260206)
	(generator "pcbnew")
	(generator_version "10.0")
	(general
		(thickness 1.6)
		(legacy_teardrops no)
	)
	(paper "A4")
	(title_block
		(title "Bryce Canyon_IOM_IOC_16318-2_OCP.brd")
		(comment 1 "Bryce Canyon / footprints 1453-1459 of 1605")
	)
	(layers
		(0 "F.Cu" signal "TOP")
		(4 "In1.Cu" signal "L2GND")
		(6 "In2.Cu" signal "L3")
		(8 "In3.Cu" signal "L4VCC")
		(10 "In4.Cu" signal "L5VCC")
		(12 "In5.Cu" signal "L6")
		(14 "In6.Cu" signal "L7GND")
		(2 "B.Cu" signal "BOTTOM")
		(9 "F.Adhes" user "F.Adhesive")
		(11 "B.Adhes" user "B.Adhesive")
		(13 "F.Paste" user "Package Geometry/Pastemask Top")
		(15 "B.Paste" user "Package Geometry/Pastemask Bottom")
		(5 "F.SilkS" user "Ref Des/Silkscreen Top")
		(7 "B.SilkS" user "Ref Des/Silkscreen Bottom")
		(1 "F.Mask" user "Board Geometry/Soldermask Top")
		(3 "B.Mask" user "Board Geometry/Soldermask Bottom")
		(17 "Dwgs.User" user "User.Drawings")
		(19 "Cmts.User" user "User.Comments")
		(21 "Eco1.User" user "User.Eco1")
		(23 "Eco2.User" user "User.Eco2")
		(25 "Edge.Cuts" user "Board Geometry/Outline")
		(27 "Margin" user)
		(31 "F.CrtYd" user "Package Geometry/Place Bound Top")
		(29 "B.CrtYd" user "Package Geometry/Place Bound Bottom")
		(35 "F.Fab" user "Ref Des/Assembly Top")
		(33 "B.Fab" user "Ref Des/Assembly Bottom")
	)
	(footprint ""
		(layer "B.Cu")
		(at 193.2051 -58.99658)
		(property "Reference" "C388"
			(at 0 0 0)
			(layer "B.SilkS")
			(hide yes)
			(effects
				(font
					(size 1.27 1.27)
				)
				(justify mirror)
			)
		)
		(property "Value" "SC10U6D3V5KX-4GP"
			(at 0.0762 -6.1214 0)
			(unlocked yes)
			(layer "B.Fab")
			(hide yes)
			(effects
				(font
					(size 1.016 1.016)
					(thickness 0.1524)
				)
				(justify mirror)
			)
		)
		(property "Device Type" "C805H58"
			(at 0.0762 -8.1534 0)
			(unlocked yes)
			(layer "B.Fab")
			(hide yes)
			(effects
				(font
					(size 1.016 1.016)
					(thickness 0.1524)
				)
				(justify mirror)
			)
		)
		(duplicate_pad_numbers_are_jumpers no)
		(fp_line
			(start -0.635 0)
			(end 0.635 0)
			(stroke
				(width 0.508)
				(type default)
			)
			(layer "B.SilkS")
		)
		(fp_rect
			(start 0.9652 1.778)
			(end -0.9652 -1.778)
			(stroke
				(width 0)
				(type default)
			)
			(fill no)
			(layer "B.CrtYd")
		)
		(fp_poly
			(pts
				(xy 0.9652 -1.778) (xy -0.9652 -1.778) (xy -0.9652 1.778) (xy 0.9652 1.778)
			)
			(stroke
				(width 0)
				(type default)
			)
			(fill no)
			(layer "B.Fab")
		)
		(pad "1" smd rect
			(at 0 -0.9652 180)
			(size 1.397 1.143)
			(layers "B.Cu" "B.Mask" "B.Paste")
			(net "P0V975")
		)
		(pad "2" smd rect
			(at 0 0.9652 180)
			(size 1.397 1.143)
			(layers "B.Cu" "B.Mask" "B.Paste")
			(net "GND")
		)
	)
	(footprint ""
		(layer "B.Cu")
		(at 169.33799 -38.442138)
		(property "Reference" "C494"
			(at 0 0 0)
			(layer "B.SilkS")
			(hide yes)
			(effects
				(font
					(size 1.27 1.27)
				)
				(justify mirror)
			)
		)
		(property "Value" "SCD01U16V1KX-GP"
			(at 2.8321 -1.7399 0)
			(unlocked yes)
			(layer "B.Fab")
			(hide yes)
			(effects
				(font
					(size 1.016 1.016)
					(thickness 0.1524)
				)
				(justify mirror)
			)
		)
		(property "Device Type" "C0201H13"
			(at 2.8321 -3.2639 0)
			(unlocked yes)
			(layer "B.Fab")
			(hide yes)
			(effects
				(font
					(size 1.016 1.016)
					(thickness 0.1524)
				)
				(justify mirror)
			)
		)
		(duplicate_pad_numbers_are_jumpers no)
		(fp_rect
			(start 0.2794 0.6477)
			(end -0.2794 -0.6477)
			(stroke
				(width 0)
				(type default)
			)
			(fill no)
			(layer "B.CrtYd")
		)
		(fp_rect
			(start 0.2794 0.6477)
			(end -0.2794 -0.6477)
			(stroke
				(width 0)
				(type default)
			)
			(fill no)
			(layer "B.Fab")
		)
		(pad "1" smd custom
			(at 0 -0.2794 180)
			(size 0.0762 0.0762)
			(layers "B.Cu" "B.Mask" "B.Paste")
			(net "PHY_CON_B_TO_IOC_0_DP")
			(options
				(clearance outline)
				(anchor circle)
			)
			(primitives
				(gr_poly
					(pts
						(arc
							(start 0.1524 0.127)
							(mid 0.137521 0.162921)
							(end 0.1016 0.1778)
						)
						(arc
							(start -0.1016 0.1778)
							(mid -0.137521 0.162921)
							(end -0.1524 0.127)
						)
						(arc
							(start -0.1524 -0.127)
							(mid -0.137521 -0.162921)
							(end -0.1016 -0.1778)
						)
						(arc
							(start 0.1016 -0.1778)
							(mid 0.137521 -0.162921)
							(end 0.1524 -0.127)
						)
					)
					(width 0)
					(fill yes)
				)
			)
		)
		(pad "2" smd custom
			(at 0 0.2794 180)
			(size 0.0762 0.0762)
			(layers "B.Cu" "B.Mask" "B.Paste")
			(net "PHY_CON_B_TO_IOC_0_DP_C")
			(options
				(clearance outline)
				(anchor circle)
			)
			(primitives
				(gr_poly
					(pts
						(arc
							(start 0.1524 0.127)
							(mid 0.137521 0.162921)
							(end 0.1016 0.1778)
						)
						(arc
							(start -0.1016 0.1778)
							(mid -0.137521 0.162921)
							(end -0.1524 0.127)
						)
						(arc
							(start -0.1524 -0.127)
							(mid -0.137521 -0.162921)
							(end -0.1016 -0.1778)
						)
						(arc
							(start 0.1016 -0.1778)
							(mid 0.137521 -0.162921)
							(end 0.1524 -0.127)
						)
					)
					(width 0)
					(fill yes)
				)
			)
		)
	)
	(footprint ""
		(layer "B.Cu")
		(at 63.000128 -147.083018 90)
		(property "Reference" "R201"
			(at 0 0 90)
			(layer "B.SilkS")
			(hide yes)
			(effects
				(font
					(size 1.27 1.27)
				)
				(justify mirror)
			)
		)
		(property "Value" "2K2R2F-GP"
			(at -0.064008 -3.993896 90)
			(unlocked yes)
			(layer "B.Fab")
			(hide yes)
			(effects
				(font
					(size 1.016 1.016)
					(thickness 0.1524)
				)
				(justify mirror)
			)
		)
		(property "Device Type" "R402H16"
			(at -0.064008 -5.517896 90)
			(unlocked yes)
			(layer "B.Fab")
			(hide yes)
			(effects
				(font
					(size 1.016 1.016)
					(thickness 0.1524)
				)
				(justify mirror)
			)
		)
		(duplicate_pad_numbers_are_jumpers no)
		(fp_line
			(start 0.508 -0.9398)
			(end 0.508 0.9398)
			(stroke
				(width 0.1524)
				(type default)
			)
			(layer "B.SilkS")
		)
		(fp_line
			(start -0.508 -0.9398)
			(end 0.508 -0.9398)
			(stroke
				(width 0.1524)
				(type default)
			)
			(layer "B.SilkS")
		)
		(fp_rect
			(start 0.508 0.9398)
			(end -0.508 -0.9398)
			(stroke
				(width 0)
				(type default)
			)
			(fill no)
			(layer "B.CrtYd")
		)
		(fp_rect
			(start 0.508 0.9398)
			(end -0.508 -0.9398)
			(stroke
				(width 0)
				(type default)
			)
			(fill no)
			(layer "B.Fab")
		)
		(pad "1" smd custom
			(at 0 -0.4445 270)
			(size 0.1397 0.1397)
			(layers "B.Cu" "B.Mask" "B.Paste")
			(net "I2C_MEZZ_FRU_SENSOR_SCL")
			(options
				(clearance outline)
				(anchor circle)
			)
			(primitives
				(gr_poly
					(pts
						(arc
							(start -0.1778 0.2794)
							(mid -0.249642 0.249642)
							(end -0.2794 0.1778)
						)
						(arc
							(start -0.2794 -0.1778)
							(mid -0.249642 -0.249642)
							(end -0.1778 -0.2794)
						)
						(arc
							(start 0.1778 -0.2794)
							(mid 0.249642 -0.249642)
							(end 0.2794 -0.1778)
						)
						(arc
							(start 0.2794 0.1778)
							(mid 0.249642 0.249642)
							(end 0.1778 0.2794)
						)
					)
					(width 0)
					(fill yes)
				)
			)
		)
		(pad "2" smd custom
			(at 0 0.4445 270)
			(size 0.1397 0.1397)
			(layers "B.Cu" "B.Mask" "B.Paste")
			(net "P3V3_STBY")
			(options
				(clearance outline)
				(anchor circle)
			)
			(primitives
				(gr_poly
					(pts
						(arc
							(start -0.1778 0.2794)
							(mid -0.249642 0.249642)
							(end -0.2794 0.1778)
						)
						(arc
							(start -0.2794 -0.1778)
							(mid -0.249642 -0.249642)
							(end -0.1778 -0.2794)
						)
						(arc
							(start 0.1778 -0.2794)
							(mid 0.249642 -0.249642)
							(end 0.2794 -0.1778)
						)
						(arc
							(start 0.2794 0.1778)
							(mid 0.249642 0.249642)
							(end 0.1778 0.2794)
						)
					)
					(width 0)
					(fill yes)
				)
			)
		)
	)
	(footprint ""
		(layer "B.Cu")
		(at 38.45941 -117.941852 90)
		(property "Reference" "R347"
			(at 0 0 90)
			(layer "B.SilkS")
			(hide yes)
			(effects
				(font
					(size 1.27 1.27)
				)
				(justify mirror)
			)
		)
		(property "Value" "4K7R2F-GP"
			(at -0.064008 -3.993896 90)
			(unlocked yes)
			(layer "B.Fab")
			(hide yes)
			(effects
				(font
					(size 1.016 1.016)
					(thickness 0.1524)
				)
				(justify mirror)
			)
		)
		(property "Device Type" "R402H16"
			(at -0.064008 -5.517896 90)
			(unlocked yes)
			(layer "B.Fab")
			(hide yes)
			(effects
				(font
					(size 1.016 1.016)
					(thickness 0.1524)
				)
				(justify mirror)
			)
		)
		(duplicate_pad_numbers_are_jumpers no)
		(fp_line
			(start 0.508 -0.9398)
			(end 0.508 0.9398)
			(stroke
				(width 0.1524)
				(type default)
			)
			(layer "B.SilkS")
		)
		(fp_line
			(start -0.508 -0.9398)
			(end 0.508 -0.9398)
			(stroke
				(width 0.1524)
				(type default)
			)
			(layer "B.SilkS")
		)
		(fp_rect
			(start 0.508 0.9398)
			(end -0.508 -0.9398)
			(stroke
				(width 0)
				(type default)
			)
			(fill no)
			(layer "B.CrtYd")
		)
		(fp_rect
			(start 0.508 0.9398)
			(end -0.508 -0.9398)
			(stroke
				(width 0)
				(type default)
			)
			(fill no)
			(layer "B.Fab")
		)
		(pad "1" smd custom
			(at 0 -0.4445 270)
			(size 0.1397 0.1397)
			(layers "B.Cu" "B.Mask" "B.Paste")
			(net "P3V3_STBY")
			(options
				(clearance outline)
				(anchor circle)
			)
			(primitives
				(gr_poly
					(pts
						(arc
							(start -0.1778 0.2794)
							(mid -0.249642 0.249642)
							(end -0.2794 0.1778)
						)
						(arc
							(start -0.2794 -0.1778)
							(mid -0.249642 -0.249642)
							(end -0.1778 -0.2794)
						)
						(arc
							(start 0.1778 -0.2794)
							(mid 0.249642 -0.249642)
							(end 0.2794 -0.1778)
						)
						(arc
							(start 0.2794 0.1778)
							(mid 0.249642 0.249642)
							(end 0.1778 0.2794)
						)
					)
					(width 0)
					(fill yes)
				)
			)
		)
		(pad "2" smd custom
			(at 0 0.4445 270)
			(size 0.1397 0.1397)
			(layers "B.Cu" "B.Mask" "B.Paste")
			(net "TEMP_3_A2")
			(options
				(clearance outline)
				(anchor circle)
			)
			(primitives
				(gr_poly
					(pts
						(arc
							(start -0.1778 0.2794)
							(mid -0.249642 0.249642)
							(end -0.2794 0.1778)
						)
						(arc
							(start -0.2794 -0.1778)
							(mid -0.249642 -0.249642)
							(end -0.1778 -0.2794)
						)
						(arc
							(start 0.1778 -0.2794)
							(mid 0.249642 -0.249642)
							(end 0.2794 -0.1778)
						)
						(arc
							(start 0.2794 0.1778)
							(mid 0.249642 0.249642)
							(end 0.1778 0.2794)
						)
					)
					(width 0)
					(fill yes)
				)
			)
		)
	)
	(footprint ""
		(layer "B.Cu")
		(at 87.796116 -177.37201)
		(property "Reference" "R93"
			(at 0 0 0)
			(layer "B.SilkS")
			(hide yes)
			(effects
				(font
					(size 1.27 1.27)
				)
				(justify mirror)
			)
		)
		(property "Value" "0R2J-2-GP"
			(at -0.064008 -3.993896 0)
			(unlocked yes)
			(layer "B.Fab")
			(hide yes)
			(effects
				(font
					(size 1.016 1.016)
					(thickness 0.1524)
				)
				(justify mirror)
			)
		)
		(property "Device Type" "R402H16"
			(at -0.064008 -5.517896 0)
			(unlocked yes)
			(layer "B.Fab")
			(hide yes)
			(effects
				(font
					(size 1.016 1.016)
					(thickness 0.1524)
				)
				(justify mirror)
			)
		)
		(duplicate_pad_numbers_are_jumpers no)
		(fp_line
			(start -0.508 -0.9398)
			(end 0.508 -0.9398)
			(stroke
				(width 0.1524)
				(type default)
			)
			(layer "B.SilkS")
		)
		(fp_line
			(start 0.508 -0.9398)
			(end 0.508 0.9398)
			(stroke
				(width 0.1524)
				(type default)
			)
			(layer "B.SilkS")
		)
		(fp_rect
			(start 0.508 0.9398)
			(end -0.508 -0.9398)
			(stroke
				(width 0)
				(type default)
			)
			(fill no)
			(layer "B.CrtYd")
		)
		(fp_rect
			(start 0.508 0.9398)
			(end -0.508 -0.9398)
			(stroke
				(width 0)
				(type default)
			)
			(fill no)
			(layer "B.Fab")
		)
		(pad "1" smd custom
			(at 0 -0.4445 180)
			(size 0.1397 0.1397)
			(layers "B.Cu" "B.Mask" "B.Paste")
			(net "I2C_BMC_COMP_SCL_OUT")
			(options
				(clearance outline)
				(anchor circle)
			)
			(primitives
				(gr_poly
					(pts
						(arc
							(start -0.1778 0.2794)
							(mid -0.249642 0.249642)
							(end -0.2794 0.1778)
						)
						(arc
							(start -0.2794 -0.1778)
							(mid -0.249642 -0.249642)
							(end -0.1778 -0.2794)
						)
						(arc
							(start 0.1778 -0.2794)
							(mid 0.249642 -0.249642)
							(end 0.2794 -0.1778)
						)
						(arc
							(start 0.2794 0.1778)
							(mid 0.249642 0.249642)
							(end 0.1778 0.2794)
						)
					)
					(width 0)
					(fill yes)
				)
			)
		)
		(pad "2" smd custom
			(at 0 0.4445 180)
			(size 0.1397 0.1397)
			(layers "B.Cu" "B.Mask" "B.Paste")
			(net "I2C_BMC_COMP_SCL_R")
			(options
				(clearance outline)
				(anchor circle)
			)
			(primitives
				(gr_poly
					(pts
						(arc
							(start -0.1778 0.2794)
							(mid -0.249642 0.249642)
							(end -0.2794 0.1778)
						)
						(arc
							(start -0.2794 -0.1778)
							(mid -0.249642 -0.249642)
							(end -0.1778 -0.2794)
						)
						(arc
							(start 0.1778 -0.2794)
							(mid 0.249642 -0.249642)
							(end 0.2794 -0.1778)
						)
						(arc
							(start 0.2794 0.1778)
							(mid 0.249642 0.249642)
							(end 0.1778 0.2794)
						)
					)
					(width 0)
					(fill yes)
				)
			)
		)
	)
	(footprint ""
		(layer "B.Cu")
		(at 93.291406 -140.716 -90)
		(property "Reference" "C137"
			(at 0 0 90)
			(layer "B.SilkS")
			(hide yes)
			(effects
				(font
					(size 1.27 1.27)
				)
				(justify mirror)
			)
		)
		(property "Value" "SCD1U16V2KX-3GP"
			(at -1.1811 -2.7051 270)
			(unlocked yes)
			(layer "B.Fab")
			(hide yes)
			(effects
				(font
					(size 1.016 1.016)
					(thickness 0.1524)
				)
				(justify mirror)
			)
		)
		(property "Device Type" "C402H22"
			(at -1.1811 -4.2291 270)
			(unlocked yes)
			(layer "B.Fab")
			(hide yes)
			(effects
				(font
					(size 1.016 1.016)
					(thickness 0.1524)
				)
				(justify mirror)
			)
		)
		(duplicate_pad_numbers_are_jumpers no)
		(fp_rect
			(start 0.4318 0.9525)
			(end -0.4318 -0.9525)
			(stroke
				(width 0)
				(type default)
			)
			(fill no)
			(layer "B.CrtYd")
		)
		(fp_rect
			(start 0.4318 0.9525)
			(end -0.4318 -0.9525)
			(stroke
				(width 0)
				(type default)
			)
			(fill no)
			(layer "B.Fab")
		)
		(pad "1" smd custom
			(at 0 -0.4445 90)
			(size 0.1524 0.1524)
			(layers "B.Cu" "B.Mask" "B.Paste")
			(net "DEBUG_CARD_PRSNT")
			(options
				(clearance outline)
				(anchor circle)
			)
			(primitives
				(gr_poly
					(pts
						(arc
							(start 0.3048 0.2032)
							(mid 0.275042 0.275042)
							(end 0.2032 0.3048)
						)
						(arc
							(start -0.2032 0.3048)
							(mid -0.275042 0.275042)
							(end -0.3048 0.2032)
						)
						(arc
							(start -0.3048 -0.2032)
							(mid -0.275042 -0.275042)
							(end -0.2032 -0.3048)
						)
						(arc
							(start 0.2032 -0.3048)
							(mid 0.275042 -0.275042)
							(end 0.3048 -0.2032)
						)
					)
					(width 0)
					(fill yes)
				)
			)
		)
		(pad "2" smd custom
			(at 0 0.4445 90)
			(size 0.1524 0.1524)
			(layers "B.Cu" "B.Mask" "B.Paste")
			(net "GND")
			(options
				(clearance outline)
				(anchor circle)
			)
			(primitives
				(gr_poly
					(pts
						(arc
							(start 0.3048 0.2032)
							(mid 0.275042 0.275042)
							(end 0.2032 0.3048)
						)
						(arc
							(start -0.2032 0.3048)
							(mid -0.275042 0.275042)
							(end -0.3048 0.2032)
						)
						(arc
							(start -0.3048 -0.2032)
							(mid -0.275042 -0.275042)
							(end -0.2032 -0.3048)
						)
						(arc
							(start 0.2032 -0.3048)
							(mid 0.275042 -0.275042)
							(end 0.3048 -0.2032)
						)
					)
					(width 0)
					(fill yes)
				)
			)
		)
	)
	(footprint ""
		(layer "B.Cu")
		(at 60.96 -142.9004 90)
		(property "Reference" "R151"
			(at 0 0 90)
			(layer "B.SilkS")
			(hide yes)
			(effects
				(font
					(size 1.27 1.27)
				)
				(justify mirror)
			)
		)
		(property "Value" "0R2J-2-GP"
			(at -0.064008 -3.993896 90)
			(unlocked yes)
			(layer "B.Fab")
			(hide yes)
			(effects
				(font
					(size 1.016 1.016)
					(thickness 0.1524)
				)
				(justify mirror)
			)
		)
		(property "Device Type" "R402H16"
			(at -0.064008 -5.517896 90)
			(unlocked yes)
			(layer "B.Fab")
			(hide yes)
			(effects
				(font
					(size 1.016 1.016)
					(thickness 0.1524)
				)
				(justify mirror)
			)
		)
		(duplicate_pad_numbers_are_jumpers no)
		(fp_line
			(start 0.508 -0.9398)
			(end 0.508 0.9398)
			(stroke
				(width 0.1524)
				(type default)
			)
			(layer "B.SilkS")
		)
		(fp_line
			(start -0.508 -0.9398)
			(end 0.508 -0.9398)
			(stroke
				(width 0.1524)
				(type default)
			)
			(layer "B.SilkS")
		)
		(fp_rect
			(start 0.508 0.9398)
			(end -0.508 -0.9398)
			(stroke
				(width 0)
				(type default)
			)
			(fill no)
			(layer "B.CrtYd")
		)
		(fp_rect
			(start 0.508 0.9398)
			(end -0.508 -0.9398)
			(stroke
				(width 0)
				(type default)
			)
			(fill no)
			(layer "B.Fab")
		)
		(pad "1" smd custom
			(at 0 -0.4445 270)
			(size 0.1397 0.1397)
			(layers "B.Cu" "B.Mask" "B.Paste")
			(net "BMC_SMB10_CLK")
			(options
				(clearance outline)
				(anchor circle)
			)
			(primitives
				(gr_poly
					(pts
						(arc
							(start -0.1778 0.2794)
							(mid -0.249642 0.249642)
							(end -0.2794 0.1778)
						)
						(arc
							(start -0.2794 -0.1778)
							(mid -0.249642 -0.249642)
							(end -0.1778 -0.2794)
						)
						(arc
							(start 0.1778 -0.2794)
							(mid 0.249642 -0.249642)
							(end 0.2794 -0.1778)
						)
						(arc
							(start 0.2794 0.1778)
							(mid 0.249642 0.249642)
							(end 0.1778 0.2794)
						)
					)
					(width 0)
					(fill yes)
				)
			)
		)
		(pad "2" smd custom
			(at 0 0.4445 270)
			(size 0.1397 0.1397)
			(layers "B.Cu" "B.Mask" "B.Paste")
			(net "I2C_EXP_LOC_SCL_OUT")
			(options
				(clearance outline)
				(anchor circle)
			)
			(primitives
				(gr_poly
					(pts
						(arc
							(start -0.1778 0.2794)
							(mid -0.249642 0.249642)
							(end -0.2794 0.1778)
						)
						(arc
							(start -0.2794 -0.1778)
							(mid -0.249642 -0.249642)
							(end -0.1778 -0.2794)
						)
						(arc
							(start 0.1778 -0.2794)
							(mid 0.249642 -0.249642)
							(end 0.2794 -0.1778)
						)
						(arc
							(start 0.2794 0.1778)
							(mid 0.249642 0.249642)
							(end 0.1778 0.2794)
						)
					)
					(width 0)
					(fill yes)
				)
			)
		)
	)
)
